(kicad_pcb
	(version 20260206)
	(generator "pcbnew")
	(generator_version "10.0")
	(general
		(thickness 1.6)
		(legacy_teardrops no)
	)
	(paper "A4")
	(title_block
		(title "04192023_DAF0TMB3IC0_F0TG_MB_C_brd_V02_OCP.brd")
		(comment 1 "Grand Teton / footprints 4973-4981 of 8354")
	)
	(layers
		(0 "F.Cu" signal "TOP")
		(4 "In1.Cu" signal "GND")
		(6 "In2.Cu" signal "IN1")
		(8 "In3.Cu" signal "GND1")
		(10 "In4.Cu" signal "IN2")
		(12 "In5.Cu" signal "GND2")
		(14 "In6.Cu" signal "IN3")
		(16 "In7.Cu" signal "GND3")
		(18 "In8.Cu" signal "VCC")
		(20 "In9.Cu" signal "VCC1")
		(22 "In10.Cu" signal "GND4")
		(24 "In11.Cu" signal "IN4")
		(26 "In12.Cu" signal "GND5")
		(28 "In13.Cu" signal "IN5")
		(30 "In14.Cu" signal "GND6")
		(32 "In15.Cu" signal "IN6")
		(34 "In16.Cu" signal "GND7")
		(2 "B.Cu" signal "BOTTOM")
		(9 "F.Adhes" user "F.Adhesive")
		(11 "B.Adhes" user "B.Adhesive")
		(13 "F.Paste" user "Package Geometry/Pastemask Top")
		(15 "B.Paste" user "Package Geometry/Pastemask Bottom")
		(5 "F.SilkS" user "Ref Des/Silkscreen Top")
		(7 "B.SilkS" user "Ref Des/Silkscreen Bottom")
		(1 "F.Mask" user "Board Geometry/Soldermask Top")
		(3 "B.Mask" user "Board Geometry/Soldermask Bottom")
		(17 "Dwgs.User" user "User.Drawings")
		(19 "Cmts.User" user "User.Comments")
		(21 "Eco1.User" user "User.Eco1")
		(23 "Eco2.User" user "User.Eco2")
		(25 "Edge.Cuts" user "Board Geometry/Outline")
		(27 "Margin" user)
		(31 "F.CrtYd" user "Package Geometry/Place Bound Top")
		(29 "B.CrtYd" user "Package Geometry/Place Bound Bottom")
		(35 "F.Fab" user "Ref Des/Assembly Top")
		(33 "B.Fab" user "Ref Des/Assembly Bottom")
	)
	(footprint ""
		(layer "B.Cu")
		(at 403.032722 -416.899344 90)
		(property "Reference" "C6618"
			(at 0 0 90)
			(layer "B.SilkS")
			(hide yes)
			(effects
				(font
					(size 1.27 1.27)
				)
				(justify mirror)
			)
		)
		(property "Value" ""
			(at 0 0 90)
			(layer "B.Fab")
			(effects
				(font
					(size 1.27 1.27)
				)
				(justify mirror)
			)
		)
		(duplicate_pad_numbers_are_jumpers no)
		(fp_line
			(start 0.299974 -0.150114)
			(end -0.299974 -0.150114)
			(stroke
				(width 0.1)
				(type default)
			)
			(layer "B.Fab")
		)
		(fp_line
			(start -0.299974 -0.150114)
			(end -0.299974 0.150114)
			(stroke
				(width 0.1)
				(type default)
			)
			(layer "B.Fab")
		)
		(fp_line
			(start 0.299974 0.150114)
			(end 0.299974 -0.150114)
			(stroke
				(width 0.1)
				(type default)
			)
			(layer "B.Fab")
		)
		(fp_line
			(start -0.299974 0.150114)
			(end 0.299974 0.150114)
			(stroke
				(width 0.1)
				(type default)
			)
			(layer "B.Fab")
		)
		(pad "1" smd rect
			(at 0.2667 0 270)
			(size 0.3048 0.381)
			(layers "B.Cu" "B.Mask" "B.Paste")
			(net "P5E_CPU0_P3_TX_BUF_C_DN<10>")
		)
		(pad "2" smd rect
			(at -0.2667 0 270)
			(size 0.3048 0.381)
			(layers "B.Cu" "B.Mask" "B.Paste")
			(net "P5E_CPU0_P3_TX_BUF_DN<10>")
		)
	)
	(footprint ""
		(layer "B.Cu")
		(at 367.595658 -145.495772 -90)
		(property "Reference" "PQ13"
			(at 1.50114 2.67335 270)
			(unlocked yes)
			(layer "B.SilkS")
			(effects
				(font
					(size 0.7874 0.5842)
					(thickness 0.1524)
				)
				(justify left mirror)
			)
		)
		(property "Value" ""
			(at 0 0 90)
			(layer "B.Fab")
			(effects
				(font
					(size 1.27 1.27)
				)
				(justify mirror)
			)
		)
		(duplicate_pad_numbers_are_jumpers no)
		(fp_line
			(start -1.603248 1.500124)
			(end 1.603248 1.500124)
			(stroke
				(width 0.1524)
				(type default)
			)
			(layer "B.SilkS")
		)
		(fp_line
			(start 1.603248 1.500124)
			(end 1.603248 -1.500124)
			(stroke
				(width 0.1524)
				(type default)
			)
			(layer "B.SilkS")
		)
		(fp_line
			(start -1.603248 -1.500124)
			(end -1.603248 1.500124)
			(stroke
				(width 0.1524)
				(type default)
			)
			(layer "B.SilkS")
		)
		(fp_line
			(start 1.603248 -1.500124)
			(end -1.603248 -1.500124)
			(stroke
				(width 0.1524)
				(type default)
			)
			(layer "B.SilkS")
		)
		(fp_line
			(start -0.700024 1.500124)
			(end -0.700024 0.219964)
			(stroke
				(width 0.1)
				(type default)
			)
			(layer "B.Fab")
		)
		(fp_line
			(start 0.700024 1.500124)
			(end -0.700024 1.500124)
			(stroke
				(width 0.1)
				(type default)
			)
			(layer "B.Fab")
		)
		(fp_line
			(start 0.700024 1.169924)
			(end 0.700024 1.500124)
			(stroke
				(width 0.1)
				(type default)
			)
			(layer "B.Fab")
		)
		(fp_line
			(start 1.249934 1.169924)
			(end 0.700024 1.169924)
			(stroke
				(width 0.1)
				(type default)
			)
			(layer "B.Fab")
		)
		(fp_line
			(start 0.6985 0.729996)
			(end 1.249934 0.729996)
			(stroke
				(width 0.1)
				(type default)
			)
			(layer "B.Fab")
		)
		(fp_line
			(start 1.249934 0.729996)
			(end 1.249934 1.169924)
			(stroke
				(width 0.1)
				(type default)
			)
			(layer "B.Fab")
		)
		(fp_line
			(start -1.249934 0.219964)
			(end -1.249934 -0.219964)
			(stroke
				(width 0.1)
				(type default)
			)
			(layer "B.Fab")
		)
		(fp_line
			(start -0.700024 0.219964)
			(end -1.249934 0.219964)
			(stroke
				(width 0.1)
				(type default)
			)
			(layer "B.Fab")
		)
		(fp_line
			(start -1.249934 -0.219964)
			(end -0.700024 -0.219964)
			(stroke
				(width 0.1)
				(type default)
			)
			(layer "B.Fab")
		)
		(fp_line
			(start -0.700024 -0.219964)
			(end -0.700024 -1.500124)
			(stroke
				(width 0.1)
				(type default)
			)
			(layer "B.Fab")
		)
		(fp_line
			(start 0.6985 -0.729996)
			(end 0.6985 0.729996)
			(stroke
				(width 0.1)
				(type default)
			)
			(layer "B.Fab")
		)
		(fp_line
			(start 1.249934 -0.729996)
			(end 0.6985 -0.729996)
			(stroke
				(width 0.1)
				(type default)
			)
			(layer "B.Fab")
		)
		(fp_line
			(start 0.700024 -1.169924)
			(end 1.249934 -1.169924)
			(stroke
				(width 0.1)
				(type default)
			)
			(layer "B.Fab")
		)
		(fp_line
			(start 1.249934 -1.169924)
			(end 1.249934 -0.729996)
			(stroke
				(width 0.1)
				(type default)
			)
			(layer "B.Fab")
		)
		(fp_line
			(start -0.700024 -1.500124)
			(end 0.700024 -1.500124)
			(stroke
				(width 0.1)
				(type default)
			)
			(layer "B.Fab")
		)
		(fp_line
			(start 0.700024 -1.500124)
			(end 0.700024 -1.169924)
			(stroke
				(width 0.1)
				(type default)
			)
			(layer "B.Fab")
		)
		(fp_rect
			(start 0.700024 1.500124)
			(end -0.700024 -1.500124)
			(stroke
				(width 0)
				(type default)
			)
			(fill no)
			(layer "B.Fab")
		)
		(pad "D" smd rect
			(at -0.999998 0 180)
			(size 0.8128 0.9144)
			(layers "B.Cu" "B.Mask" "B.Paste")
			(net "PVDDCR_SOC_P0_EN//ADDR_CFG")
		)
		(pad "G" smd rect
			(at 0.999998 -0.94996 180)
			(size 0.8128 0.9144)
			(layers "B.Cu" "B.Mask" "B.Paste")
			(net "PVDDCR_SOC_P0_EN_GD")
		)
		(pad "S" smd rect
			(at 0.999998 0.94996 180)
			(size 0.8128 0.9144)
			(layers "B.Cu" "B.Mask" "B.Paste")
			(net "P3V3_AUX")
		)
	)
	(footprint ""
		(layer "B.Cu")
		(at 435.029102 -351.058226 90)
		(property "Reference" "PC212_2"
			(at 0 0 90)
			(layer "B.SilkS")
			(hide yes)
			(effects
				(font
					(size 1.27 1.27)
				)
				(justify mirror)
			)
		)
		(property "Value" ""
			(at 0 0 90)
			(layer "B.Fab")
			(effects
				(font
					(size 1.27 1.27)
				)
				(justify mirror)
			)
		)
		(duplicate_pad_numbers_are_jumpers no)
		(fp_line
			(start 1.524 -0.762)
			(end -1.524 -0.762)
			(stroke
				(width 0.1524)
				(type default)
			)
			(layer "B.SilkS")
		)
		(fp_line
			(start -1.524 -0.762)
			(end -1.524 0.762)
			(stroke
				(width 0.1524)
				(type default)
			)
			(layer "B.SilkS")
		)
		(fp_line
			(start 1.524 0.762)
			(end 1.524 -0.762)
			(stroke
				(width 0.1524)
				(type default)
			)
			(layer "B.SilkS")
		)
		(fp_line
			(start -1.524 0.762)
			(end 1.524 0.762)
			(stroke
				(width 0.1524)
				(type default)
			)
			(layer "B.SilkS")
		)
		(fp_line
			(start 1.1049 -0.724916)
			(end 1.1049 0.724916)
			(stroke
				(width 0.1)
				(type default)
			)
			(layer "B.Fab")
		)
		(fp_line
			(start -1.1049 -0.724916)
			(end 1.1049 -0.724916)
			(stroke
				(width 0.1)
				(type default)
			)
			(layer "B.Fab")
		)
		(fp_line
			(start 1.1049 0.724916)
			(end -1.1049 0.724916)
			(stroke
				(width 0.1)
				(type default)
			)
			(layer "B.Fab")
		)
		(fp_line
			(start -1.1049 0.724916)
			(end -1.1049 -0.724916)
			(stroke
				(width 0.1)
				(type default)
			)
			(layer "B.Fab")
		)
		(pad "1" smd rect
			(at 0.889 0 90)
			(size 1.016 1.27)
			(layers "B.Cu" "B.Mask" "B.Paste")
			(net "SW_P12V_AUX_PVDD11_S3_P0_FLT")
		)
		(pad "2" smd rect
			(at -0.889 0 90)
			(size 1.016 1.27)
			(layers "B.Cu" "B.Mask" "B.Paste")
			(net "GND")
		)
	)
	(footprint ""
		(layer "B.Cu")
		(at 38.002718 -350.660716 -90)
		(property "Reference" "PC628_3"
			(at 0 0 90)
			(layer "B.SilkS")
			(hide yes)
			(effects
				(font
					(size 1.27 1.27)
				)
				(justify mirror)
			)
		)
		(property "Value" ""
			(at 0 0 90)
			(layer "B.Fab")
			(effects
				(font
					(size 1.27 1.27)
				)
				(justify mirror)
			)
		)
		(duplicate_pad_numbers_are_jumpers no)
		(fp_line
			(start -1.524 0.762)
			(end 1.524 0.762)
			(stroke
				(width 0.1524)
				(type default)
			)
			(layer "B.SilkS")
		)
		(fp_line
			(start 1.524 0.762)
			(end 1.524 -0.762)
			(stroke
				(width 0.1524)
				(type default)
			)
			(layer "B.SilkS")
		)
		(fp_line
			(start -1.524 -0.762)
			(end -1.524 0.762)
			(stroke
				(width 0.1524)
				(type default)
			)
			(layer "B.SilkS")
		)
		(fp_line
			(start 1.524 -0.762)
			(end -1.524 -0.762)
			(stroke
				(width 0.1524)
				(type default)
			)
			(layer "B.SilkS")
		)
		(fp_line
			(start -1.1049 0.724916)
			(end -1.1049 -0.724916)
			(stroke
				(width 0.1)
				(type default)
			)
			(layer "B.Fab")
		)
		(fp_line
			(start 1.1049 0.724916)
			(end -1.1049 0.724916)
			(stroke
				(width 0.1)
				(type default)
			)
			(layer "B.Fab")
		)
		(fp_line
			(start -1.1049 -0.724916)
			(end 1.1049 -0.724916)
			(stroke
				(width 0.1)
				(type default)
			)
			(layer "B.Fab")
		)
		(fp_line
			(start 1.1049 -0.724916)
			(end 1.1049 0.724916)
			(stroke
				(width 0.1)
				(type default)
			)
			(layer "B.Fab")
		)
		(pad "1" smd rect
			(at 0.889 0 270)
			(size 1.016 1.27)
			(layers "B.Cu" "B.Mask" "B.Paste")
			(net "SW_P12V_AUX_PVDDIO_P1_FLT")
		)
		(pad "2" smd rect
			(at -0.889 0 270)
			(size 1.016 1.27)
			(layers "B.Cu" "B.Mask" "B.Paste")
			(net "GND")
		)
	)
	(footprint ""
		(layer "B.Cu")
		(at 330.94041 -397.228568)
		(property "Reference" "C637"
			(at 0 0 0)
			(layer "B.SilkS")
			(hide yes)
			(effects
				(font
					(size 1.27 1.27)
				)
				(justify mirror)
			)
		)
		(property "Value" ""
			(at 0 0 0)
			(layer "B.Fab")
			(effects
				(font
					(size 1.27 1.27)
				)
				(justify mirror)
			)
		)
		(duplicate_pad_numbers_are_jumpers no)
		(fp_line
			(start -1.524 -0.762)
			(end -1.524 0.762)
			(stroke
				(width 0.1524)
				(type default)
			)
			(layer "B.SilkS")
		)
		(fp_line
			(start -1.524 0.762)
			(end 1.524 0.762)
			(stroke
				(width 0.1524)
				(type default)
			)
			(layer "B.SilkS")
		)
		(fp_line
			(start 1.524 -0.762)
			(end -1.524 -0.762)
			(stroke
				(width 0.1524)
				(type default)
			)
			(layer "B.SilkS")
		)
		(fp_line
			(start 1.524 0.762)
			(end 1.524 -0.762)
			(stroke
				(width 0.1524)
				(type default)
			)
			(layer "B.SilkS")
		)
		(fp_line
			(start -1.1049 -0.724916)
			(end 1.1049 -0.724916)
			(stroke
				(width 0.1)
				(type default)
			)
			(layer "B.Fab")
		)
		(fp_line
			(start -1.1049 0.724916)
			(end -1.1049 -0.724916)
			(stroke
				(width 0.1)
				(type default)
			)
			(layer "B.Fab")
		)
		(fp_line
			(start 1.1049 -0.724916)
			(end 1.1049 0.724916)
			(stroke
				(width 0.1)
				(type default)
			)
			(layer "B.Fab")
		)
		(fp_line
			(start 1.1049 0.724916)
			(end -1.1049 0.724916)
			(stroke
				(width 0.1)
				(type default)
			)
			(layer "B.Fab")
		)
		(pad "1" smd rect
			(at 0.889 0)
			(size 1.016 1.27)
			(layers "B.Cu" "B.Mask" "B.Paste")
			(net "P0V9_CPU0_RT1_2A")
		)
		(pad "2" smd rect
			(at -0.889 0)
			(size 1.016 1.27)
			(layers "B.Cu" "B.Mask" "B.Paste")
			(net "GND")
		)
	)
	(footprint ""
		(layer "B.Cu")
		(at 371.553486 -182.676038 -90)
		(property "Reference" "PC488_2"
			(at 0 0 90)
			(layer "B.SilkS")
			(hide yes)
			(effects
				(font
					(size 1.27 1.27)
				)
				(justify mirror)
			)
		)
		(property "Value" ""
			(at 0 0 90)
			(layer "B.Fab")
			(effects
				(font
					(size 1.27 1.27)
				)
				(justify mirror)
			)
		)
		(duplicate_pad_numbers_are_jumpers no)
		(fp_line
			(start -1.524 0.762)
			(end 1.524 0.762)
			(stroke
				(width 0.1524)
				(type default)
			)
			(layer "B.SilkS")
		)
		(fp_line
			(start 1.524 0.762)
			(end 1.524 -0.762)
			(stroke
				(width 0.1524)
				(type default)
			)
			(layer "B.SilkS")
		)
		(fp_line
			(start -1.524 -0.762)
			(end -1.524 0.762)
			(stroke
				(width 0.1524)
				(type default)
			)
			(layer "B.SilkS")
		)
		(fp_line
			(start 1.524 -0.762)
			(end -1.524 -0.762)
			(stroke
				(width 0.1524)
				(type default)
			)
			(layer "B.SilkS")
		)
		(fp_line
			(start -1.1049 0.724916)
			(end -1.1049 -0.724916)
			(stroke
				(width 0.1)
				(type default)
			)
			(layer "B.Fab")
		)
		(fp_line
			(start 1.1049 0.724916)
			(end -1.1049 0.724916)
			(stroke
				(width 0.1)
				(type default)
			)
			(layer "B.Fab")
		)
		(fp_line
			(start -1.1049 -0.724916)
			(end 1.1049 -0.724916)
			(stroke
				(width 0.1)
				(type default)
			)
			(layer "B.Fab")
		)
		(fp_line
			(start 1.1049 -0.724916)
			(end 1.1049 0.724916)
			(stroke
				(width 0.1)
				(type default)
			)
			(layer "B.Fab")
		)
		(pad "1" smd rect
			(at 0.889 0 270)
			(size 1.016 1.27)
			(layers "B.Cu" "B.Mask" "B.Paste")
			(net "SW_P12V_AUX_PVDDCR_CPU0_P0_FLT")
		)
		(pad "2" smd rect
			(at -0.889 0 270)
			(size 1.016 1.27)
			(layers "B.Cu" "B.Mask" "B.Paste")
			(net "GND")
		)
	)
	(footprint ""
		(layer "B.Cu")
		(at 156.67101 -16.851122 -90)
		(property "Reference" "R2999"
			(at 0 0 90)
			(layer "B.SilkS")
			(hide yes)
			(effects
				(font
					(size 1.27 1.27)
				)
				(justify mirror)
			)
		)
		(property "Value" ""
			(at 0 0 90)
			(layer "B.Fab")
			(effects
				(font
					(size 1.27 1.27)
				)
				(justify mirror)
			)
		)
		(duplicate_pad_numbers_are_jumpers no)
		(fp_line
			(start -0.7874 0.4064)
			(end 0.7874 0.4064)
			(stroke
				(width 0.1524)
				(type default)
			)
			(layer "B.SilkS")
		)
		(fp_line
			(start 0.7874 0.4064)
			(end 0.7874 -0.4064)
			(stroke
				(width 0.1524)
				(type default)
			)
			(layer "B.SilkS")
		)
		(fp_line
			(start -0.7874 -0.4064)
			(end -0.7874 0.4064)
			(stroke
				(width 0.1524)
				(type default)
			)
			(layer "B.SilkS")
		)
		(fp_line
			(start 0.7874 -0.4064)
			(end -0.7874 -0.4064)
			(stroke
				(width 0.1524)
				(type default)
			)
			(layer "B.SilkS")
		)
		(fp_line
			(start -0.67945 0.3048)
			(end -0.120396 0.3048)
			(stroke
				(width 0.1)
				(type default)
			)
			(layer "B.Fab")
		)
		(fp_line
			(start -0.120396 0.3048)
			(end -0.120396 0.2794)
			(stroke
				(width 0.1)
				(type default)
			)
			(layer "B.Fab")
		)
		(fp_line
			(start 0.12065 0.3048)
			(end 0.67945 0.3048)
			(stroke
				(width 0.1)
				(type default)
			)
			(layer "B.Fab")
		)
		(fp_line
			(start 0.67945 0.3048)
			(end 0.67945 -0.305054)
			(stroke
				(width 0.1)
				(type default)
			)
			(layer "B.Fab")
		)
		(fp_line
			(start -0.120396 0.2794)
			(end 0.12065 0.2794)
			(stroke
				(width 0.1)
				(type default)
			)
			(layer "B.Fab")
		)
		(fp_line
			(start 0.12065 0.2794)
			(end 0.12065 0.3048)
			(stroke
				(width 0.1)
				(type default)
			)
			(layer "B.Fab")
		)
		(fp_line
			(start -0.12065 -0.2794)
			(end -0.12065 -0.3048)
			(stroke
				(width 0.1)
				(type default)
			)
			(layer "B.Fab")
		)
		(fp_line
			(start 0.12065 -0.2794)
			(end -0.12065 -0.2794)
			(stroke
				(width 0.1)
				(type default)
			)
			(layer "B.Fab")
		)
		(fp_line
			(start -0.67945 -0.3048)
			(end -0.67945 0.3048)
			(stroke
				(width 0.1)
				(type default)
			)
			(layer "B.Fab")
		)
		(fp_line
			(start -0.12065 -0.3048)
			(end -0.67945 -0.3048)
			(stroke
				(width 0.1)
				(type default)
			)
			(layer "B.Fab")
		)
		(fp_line
			(start 0.12065 -0.305054)
			(end 0.12065 -0.2794)
			(stroke
				(width 0.1)
				(type default)
			)
			(layer "B.Fab")
		)
		(fp_line
			(start 0.67945 -0.305054)
			(end 0.12065 -0.305054)
			(stroke
				(width 0.1)
				(type default)
			)
			(layer "B.Fab")
		)
		(pad "1" smd circle
			(at 0.40005 0 90)
			(size 0 0)
			(layers "B.Cu" "B.Mask" "B.Paste")
			(net "SMB_2_BMC_GPU_SCL")
		)
		(pad "2" smd circle
			(at -0.40005 0 90)
			(size 0 0)
			(layers "B.Cu" "B.Mask" "B.Paste")
			(net "P3V3_AUX")
		)
	)
	(footprint ""
		(layer "B.Cu")
		(at 61.778642 -386.766562 90)
		(property "Reference" "C190"
			(at 0 0 90)
			(layer "B.SilkS")
			(hide yes)
			(effects
				(font
					(size 1.27 1.27)
				)
				(justify mirror)
			)
		)
		(property "Value" ""
			(at 0 0 90)
			(layer "B.Fab")
			(effects
				(font
					(size 1.27 1.27)
				)
				(justify mirror)
			)
		)
		(duplicate_pad_numbers_are_jumpers no)
		(fp_line
			(start 0.299974 -0.150114)
			(end -0.299974 -0.150114)
			(stroke
				(width 0.1)
				(type default)
			)
			(layer "B.Fab")
		)
		(fp_line
			(start -0.299974 -0.150114)
			(end -0.299974 0.150114)
			(stroke
				(width 0.1)
				(type default)
			)
			(layer "B.Fab")
		)
		(fp_line
			(start 0.299974 0.150114)
			(end 0.299974 -0.150114)
			(stroke
				(width 0.1)
				(type default)
			)
			(layer "B.Fab")
		)
		(fp_line
			(start -0.299974 0.150114)
			(end 0.299974 0.150114)
			(stroke
				(width 0.1)
				(type default)
			)
			(layer "B.Fab")
		)
		(pad "1" smd rect
			(at 0.2667 0 270)
			(size 0.3048 0.381)
			(layers "B.Cu" "B.Mask" "B.Paste")
			(net "P0V9_CPU1_RT0_2A")
		)
		(pad "2" smd rect
			(at -0.2667 0 270)
			(size 0.3048 0.381)
			(layers "B.Cu" "B.Mask" "B.Paste")
			(net "GND")
		)
	)
	(footprint ""
		(layer "B.Cu")
		(at 382.504442 -416.899344 90)
		(property "Reference" "C6603"
			(at 0 0 90)
			(layer "B.SilkS")
			(hide yes)
			(effects
				(font
					(size 1.27 1.27)
				)
				(justify mirror)
			)
		)
		(property "Value" ""
			(at 0 0 90)
			(layer "B.Fab")
			(effects
				(font
					(size 1.27 1.27)
				)
				(justify mirror)
			)
		)
		(duplicate_pad_numbers_are_jumpers no)
		(fp_line
			(start 0.299974 -0.150114)
			(end -0.299974 -0.150114)
			(stroke
				(width 0.1)
				(type default)
			)
			(layer "B.Fab")
		)
		(fp_line
			(start -0.299974 -0.150114)
			(end -0.299974 0.150114)
			(stroke
				(width 0.1)
				(type default)
			)
			(layer "B.Fab")
		)
		(fp_line
			(start 0.299974 0.150114)
			(end 0.299974 -0.150114)
			(stroke
				(width 0.1)
				(type default)
			)
			(layer "B.Fab")
		)
		(fp_line
			(start -0.299974 0.150114)
			(end 0.299974 0.150114)
			(stroke
				(width 0.1)
				(type default)
			)
			(layer "B.Fab")
		)
		(pad "1" smd rect
			(at 0.2667 0 270)
			(size 0.3048 0.381)
			(layers "B.Cu" "B.Mask" "B.Paste")
			(net "P5E_CPU0_P3_TX_BUF_C_DP<3>")
		)
		(pad "2" smd rect
			(at -0.2667 0 270)
			(size 0.3048 0.381)
			(layers "B.Cu" "B.Mask" "B.Paste")
			(net "P5E_CPU0_P3_TX_BUF_DP<3>")
		)
	)
)
